# BASEBOARD_FAB2 (Tioga Pass) — schematic netlist excerpt (pin names and nets, part order shuffled) for the footprints in the layout excerpt that follows; sources: Cadence DE-HDL packaged netlist, KiCad conversion of Wiwynn_Tioga_Pass_MB.brd

R25W22  120R2F-GP  1%  pkg RCL_GP  page 151 : \1\ = GND ; \2\ = BMC_M_A10
R6N14  RES  1.00K 1% CHIP  pkg 0402  page 156 : A = GND ; B = PD_PIROM_CPU0_ADDR0
R7W22  RES  4.75K 1% CHIP  pkg 0402  page 119 : A = P3V3_STBY ; B = FM_BMC_ENABLE_N

(kicad_pcb
	(version 20260206)
	(generator "pcbnew")
	(generator_version "10.0")
	(general
		(thickness 1.6)
		(legacy_teardrops no)
	)
	(paper "A4")
	(title_block
		(title "Wiwynn_Tioga_Pass_MB.brd")
		(comment 1 "Tioga Pass / footprints 2345-2347 of 4770")
	)
	(layers
		(0 "F.Cu" signal "TOP")
		(4 "In1.Cu" signal "L2GND")
		(6 "In2.Cu" signal "L3")
		(8 "In3.Cu" signal "L4GND")
		(10 "In4.Cu" signal "L5")
		(12 "In5.Cu" signal "L6GND")
		(14 "In6.Cu" signal "L7VCC")
		(16 "In7.Cu" signal "L8VCC")
		(18 "In8.Cu" signal "L9GND")
		(20 "In9.Cu" signal "L10")
		(22 "In10.Cu" signal "L11GND")
		(24 "In11.Cu" signal "L12")
		(26 "In12.Cu" signal "L13GND")
		(2 "B.Cu" signal "BOTTOM")
		(9 "F.Adhes" user "F.Adhesive")
		(11 "B.Adhes" user "B.Adhesive")
		(13 "F.Paste" user "Package Geometry/Pastemask Top")
		(15 "B.Paste" user "Package Geometry/Pastemask Bottom")
		(5 "F.SilkS" user "Ref Des/Silkscreen Top")
		(7 "B.SilkS" user "Ref Des/Silkscreen Bottom")
		(1 "F.Mask" user "Board Geometry/Soldermask Top")
		(3 "B.Mask" user "Board Geometry/Soldermask Bottom")
		(17 "Dwgs.User" user "User.Drawings")
		(19 "Cmts.User" user "User.Comments")
		(21 "Eco1.User" user "User.Eco1")
		(23 "Eco2.User" user "User.Eco2")
		(25 "Edge.Cuts" user "Board Geometry/Outline")
		(27 "Margin" user)
		(31 "F.CrtYd" user "Package Geometry/Place Bound Top")
		(29 "B.CrtYd" user "Package Geometry/Place Bound Bottom")
		(35 "F.Fab" user "Ref Des/Assembly Top")
		(33 "B.Fab" user "Ref Des/Assembly Bottom")
	)
	(footprint ""
		(layer "B.Cu")
		(at 193.8528 -102.6668 180)
		(property "Reference" "R6N14"
			(at 0 0 0)
			(layer "B.SilkS")
			(hide yes)
			(effects
				(font
					(size 1.27 1.27)
				)
				(justify mirror)
			)
		)
		(property "Value" ""
			(at 0 0 0)
			(layer "B.Fab")
			(effects
				(font
					(size 1.27 1.27)
				)
				(justify mirror)
			)
		)
		(duplicate_pad_numbers_are_jumpers no)
		(fp_poly
			(pts
				(xy 0.2794 -0.1016) (xy -0.2794 -0.1016) (xy -0.2794 0.9906) (xy 0.2794 0.9906)
			)
			(stroke
				(width 0)
				(type default)
			)
			(fill no)
			(layer "B.CrtYd")
		)
		(fp_line
			(start 0.2794 0.9906)
			(end -0.2794 0.9906)
			(stroke
				(width 0.1)
				(type default)
			)
			(layer "B.Fab")
		)
		(fp_line
			(start 0.2794 -0.1016)
			(end 0.2794 0.9906)
			(stroke
				(width 0.1)
				(type default)
			)
			(layer "B.Fab")
		)
		(fp_line
			(start -0.2794 0.9906)
			(end -0.2794 -0.1016)
			(stroke
				(width 0.1)
				(type default)
			)
			(layer "B.Fab")
		)
		(fp_line
			(start -0.2794 -0.1016)
			(end 0.2794 -0.1016)
			(stroke
				(width 0.1)
				(type default)
			)
			(layer "B.Fab")
		)
		(pad "1" smd rect
			(at 0 0)
			(size 0.508 0.508)
			(layers "B.Cu" "B.Mask" "B.Paste")
			(net "GND")
		)
		(pad "2" smd rect
			(at 0 0.889)
			(size 0.508 0.508)
			(layers "B.Cu" "B.Mask" "B.Paste")
			(net "PD_PIROM_CPU0_ADDR0")
		)
		(zone
			(layer "B.Cu")
			(hatch none 0.5)
			(connect_pads
				(clearance 0)
			)
			(min_thickness 0.25)
			(keepout
				(tracks not_allowed)
				(vias allowed)
				(pads allowed)
				(copperpour not_allowed)
				(footprints allowed)
			)
			(placement
				(enabled no)
				(sheetname "")
			)
			(fill
				(thermal_gap 0.5)
				(thermal_bridge_width 0.5)
				(island_removal_mode 0)
			)
			(polygon
				(pts
					(xy 193.5988 -103.3018) (xy 194.1068 -103.3018) (xy 194.1068 -102.9208) (xy 193.5988 -102.9208)
				)
			)
		)
		(zone
			(layer "B.Cu")
			(hatch none 0.5)
			(connect_pads
				(clearance 0)
			)
			(min_thickness 0.25)
			(keepout
				(tracks allowed)
				(vias not_allowed)
				(pads allowed)
				(copperpour not_allowed)
				(footprints allowed)
			)
			(placement
				(enabled no)
				(sheetname "")
			)
			(fill
				(thermal_gap 0.5)
				(thermal_bridge_width 0.5)
				(island_removal_mode 0)
			)
			(polygon
				(pts
					(xy 193.5988 -102.9208) (xy 194.1068 -102.9208) (xy 194.1068 -103.3018) (xy 193.5988 -103.3018)
				)
			)
		)
	)
	(footprint ""
		(layer "B.Cu")
		(at 446.381632 -34.7345 90)
		(property "Reference" "R25W22"
			(at 0 0 90)
			(layer "B.SilkS")
			(hide yes)
			(effects
				(font
					(size 1.27 1.27)
				)
				(justify mirror)
			)
		)
		(property "Value" "*"
			(at -0.064008 -4.108196 90)
			(unlocked yes)
			(layer "B.Fab")
			(hide yes)
			(effects
				(font
					(size 1.27 1.016)
					(thickness 0.1524)
				)
				(justify mirror)
			)
		)
		(property "Device Type" "120R2F-GP_RCL_GP-120R2F-GP,64.A"
			(at -0.064008 -5.632196 90)
			(unlocked yes)
			(layer "B.Fab")
			(hide yes)
			(effects
				(font
					(size 1.27 1.016)
					(thickness 0.1524)
				)
				(justify mirror)
			)
		)
		(duplicate_pad_numbers_are_jumpers no)
		(fp_line
			(start 0.508 -0.9398)
			(end 0.508 0.9398)
			(stroke
				(width 0.1524)
				(type default)
			)
			(layer "B.SilkS")
		)
		(fp_line
			(start -0.508 -0.9398)
			(end 0.508 -0.9398)
			(stroke
				(width 0.1524)
				(type default)
			)
			(layer "B.SilkS")
		)
		(fp_rect
			(start 0.508 0.9398)
			(end -0.508 -0.9398)
			(stroke
				(width 0)
				(type default)
			)
			(fill no)
			(layer "B.CrtYd")
		)
		(fp_rect
			(start 0.508 0.9398)
			(end -0.508 -0.9398)
			(stroke
				(width 0)
				(type default)
			)
			(fill no)
			(layer "B.Fab")
		)
		(pad "1" smd custom
			(at 0 -0.4445 270)
			(size 0.1397 0.1397)
			(layers "B.Cu" "B.Mask" "B.Paste")
			(net "GND")
			(options
				(clearance outline)
				(anchor circle)
			)
			(primitives
				(gr_poly
					(pts
						(arc
							(start -0.1778 0.2794)
							(mid -0.249642 0.249642)
							(end -0.2794 0.1778)
						)
						(arc
							(start -0.2794 -0.1778)
							(mid -0.249642 -0.249642)
							(end -0.1778 -0.2794)
						)
						(arc
							(start 0.1778 -0.2794)
							(mid 0.249642 -0.249642)
							(end 0.2794 -0.1778)
						)
						(arc
							(start 0.2794 0.1778)
							(mid 0.249642 0.249642)
							(end 0.1778 0.2794)
						)
					)
					(width 0)
					(fill yes)
				)
			)
		)
		(pad "2" smd custom
			(at 0 0.4445 270)
			(size 0.1397 0.1397)
			(layers "B.Cu" "B.Mask" "B.Paste")
			(net "BMC_M_A10")
			(options
				(clearance outline)
				(anchor circle)
			)
			(primitives
				(gr_poly
					(pts
						(arc
							(start -0.1778 0.2794)
							(mid -0.249642 0.249642)
							(end -0.2794 0.1778)
						)
						(arc
							(start -0.2794 -0.1778)
							(mid -0.249642 -0.249642)
							(end -0.1778 -0.2794)
						)
						(arc
							(start 0.1778 -0.2794)
							(mid 0.249642 -0.249642)
							(end 0.2794 -0.1778)
						)
						(arc
							(start 0.2794 0.1778)
							(mid 0.249642 0.249642)
							(end 0.1778 0.2794)
						)
					)
					(width 0)
					(fill yes)
				)
			)
		)
	)
	(footprint ""
		(layer "B.Cu")
		(at 412.186882 -106.565192 90)
		(property "Reference" "R7W22"
			(at 0.8382 -0.67818 90)
			(unlocked yes)
			(layer "B.SilkS")
			(effects
				(font
					(size 0.4064 0.254)
					(thickness 0.1524)
				)
				(justify left mirror)
			)
		)
		(property "Value" ""
			(at 0 0 90)
			(layer "B.Fab")
			(effects
				(font
					(size 1.27 1.27)
				)
				(justify mirror)
			)
		)
		(duplicate_pad_numbers_are_jumpers no)
		(fp_poly
			(pts
				(xy 0.2794 -0.1016) (xy -0.2794 -0.1016) (xy -0.2794 0.9906) (xy 0.2794 0.9906)
			)
			(stroke
				(width 0)
				(type default)
			)
			(fill no)
			(layer "B.CrtYd")
		)
		(fp_line
			(start 0.2794 -0.1016)
			(end 0.2794 0.9906)
			(stroke
				(width 0.1)
				(type default)
			)
			(layer "B.Fab")
		)
		(fp_line
			(start -0.2794 -0.1016)
			(end 0.2794 -0.1016)
			(stroke
				(width 0.1)
				(type default)
			)
			(layer "B.Fab")
		)
		(fp_line
			(start 0.2794 0.9906)
			(end -0.2794 0.9906)
			(stroke
				(width 0.1)
				(type default)
			)
			(layer "B.Fab")
		)
		(fp_line
			(start -0.2794 0.9906)
			(end -0.2794 -0.1016)
			(stroke
				(width 0.1)
				(type default)
			)
			(layer "B.Fab")
		)
		(pad "1" smd rect
			(at 0 0 270)
			(size 0.508 0.508)
			(layers "B.Cu" "B.Mask" "B.Paste")
			(net "P3V3_STBY")
		)
		(pad "2" smd rect
			(at 0 0.889 270)
			(size 0.508 0.508)
			(layers "B.Cu" "B.Mask" "B.Paste")
			(net "FM_BMC_ENABLE_N")
		)
		(zone
			(layer "B.Cu")
			(hatch none 0.5)
			(connect_pads
				(clearance 0)
			)
			(min_thickness 0.25)
			(keepout
				(tracks allowed)
				(vias not_allowed)
				(pads allowed)
				(copperpour not_allowed)
				(footprints allowed)
			)
			(placement
				(enabled no)
				(sheetname "")
			)
			(fill
				(thermal_gap 0.5)
				(thermal_bridge_width 0.5)
				(island_removal_mode 0)
			)
			(polygon
				(pts
					(xy 412.440882 -106.819192) (xy 412.440882 -106.311192) (xy 412.821882 -106.311192) (xy 412.821882 -106.819192)
				)
			)
		)
		(zone
			(layer "B.Cu")
			(hatch none 0.5)
			(connect_pads
				(clearance 0)
			)
			(min_thickness 0.25)
			(keepout
				(tracks not_allowed)
				(vias allowed)
				(pads allowed)
				(copperpour not_allowed)
				(footprints allowed)
			)
			(placement
				(enabled no)
				(sheetname "")
			)
			(fill
				(thermal_gap 0.5)
				(thermal_bridge_width 0.5)
				(island_removal_mode 0)
			)
			(polygon
				(pts
					(xy 412.821882 -106.819192) (xy 412.821882 -106.311192) (xy 412.440882 -106.311192) (xy 412.440882 -106.819192)
				)
			)
		)
	)
)
